# S9S_MB_2U (Grand Teton) — schematic netlist excerpt (pin names and nets, part order shuffled) for the footprints in the layout excerpt that follows; sources: Cadence DE-HDL packaged netlist, KiCad conversion of 03242023_DA0F0TMBIJ0_F0T_Motherboard_J_brd_V01_OCP.brd

R3587  Q_RES  33.2 1% CHIP  pkg 0402LF  page 232 : A = SMB_INA230_3V3AUX_SDA ; B = SMB_INA230_1_3V3AUX_SDA_R
R1869  Q_RES  10 1% CHIP  pkg 0402LF  page 202 : A = ESPI_LAD0_DATA_IO2 ; B = ESPI_LPC_LAD0_IO2
PL32  Q_INDUCTOR  50NH/148A IND  pkg SMLF  page 285 : \1\ = P12V_AUX ; \2\ = SW_P12V_PVCCIN_CPU1_FLT

(kicad_pcb
	(version 20260206)
	(generator "pcbnew")
	(generator_version "10.0")
	(general
		(thickness 1.6)
		(legacy_teardrops no)
	)
	(paper "A4")
	(title_block
		(title "03242023_DA0F0TMBIJ0_F0T_Motherboard_J_brd_V01_OCP.brd")
		(comment 1 "Grand Teton / footprints 212-214 of 6105")
	)
	(layers
		(0 "F.Cu" signal "TOP")
		(4 "In1.Cu" signal "GND")
		(6 "In2.Cu" signal "IN1")
		(8 "In3.Cu" signal "GND1")
		(10 "In4.Cu" signal "IN2")
		(12 "In5.Cu" signal "GND2")
		(14 "In6.Cu" signal "IN3")
		(16 "In7.Cu" signal "GND3")
		(18 "In8.Cu" signal "VCC")
		(20 "In9.Cu" signal "VCC1")
		(22 "In10.Cu" signal "GND4")
		(24 "In11.Cu" signal "IN4")
		(26 "In12.Cu" signal "GND5")
		(28 "In13.Cu" signal "IN5")
		(30 "In14.Cu" signal "GND6")
		(32 "In15.Cu" signal "IN6")
		(34 "In16.Cu" signal "GND7")
		(2 "B.Cu" signal "BOTTOM")
		(9 "F.Adhes" user "F.Adhesive")
		(11 "B.Adhes" user "B.Adhesive")
		(13 "F.Paste" user "Package Geometry/Pastemask Top")
		(15 "B.Paste" user "Package Geometry/Pastemask Bottom")
		(5 "F.SilkS" user "Ref Des/Silkscreen Top")
		(7 "B.SilkS" user "Ref Des/Silkscreen Bottom")
		(1 "F.Mask" user "Board Geometry/Soldermask Top")
		(3 "B.Mask" user "Board Geometry/Soldermask Bottom")
		(17 "Dwgs.User" user "User.Drawings")
		(19 "Cmts.User" user "User.Comments")
		(21 "Eco1.User" user "User.Eco1")
		(23 "Eco2.User" user "User.Eco2")
		(25 "Edge.Cuts" user "Board Geometry/Outline")
		(27 "Margin" user)
		(31 "F.CrtYd" user "Package Geometry/Place Bound Top")
		(29 "B.CrtYd" user "Package Geometry/Place Bound Bottom")
		(35 "F.Fab" user "Ref Des/Assembly Top")
		(33 "B.Fab" user "Ref Des/Assembly Bottom")
	)
	(footprint ""
		(layer "F.Cu")
		(at 332.970124 -25.956006 -90)
		(property "Reference" "R1869"
			(at 0 0 270)
			(layer "F.SilkS")
			(hide yes)
			(effects
				(font
					(size 1.27 1.27)
				)
			)
		)
		(property "Value" ""
			(at 0 0 270)
			(layer "F.Fab")
			(effects
				(font
					(size 1.27 1.27)
				)
			)
		)
		(duplicate_pad_numbers_are_jumpers no)
		(fp_line
			(start -0.7874 0.4064)
			(end -0.7874 -0.4064)
			(stroke
				(width 0.1524)
				(type default)
			)
			(layer "F.SilkS")
		)
		(fp_line
			(start 0.7874 0.4064)
			(end -0.7874 0.4064)
			(stroke
				(width 0.1524)
				(type default)
			)
			(layer "F.SilkS")
		)
		(fp_line
			(start -0.7874 -0.4064)
			(end 0.7874 -0.4064)
			(stroke
				(width 0.1524)
				(type default)
			)
			(layer "F.SilkS")
		)
		(fp_line
			(start 0.7874 -0.4064)
			(end 0.7874 0.4064)
			(stroke
				(width 0.1524)
				(type default)
			)
			(layer "F.SilkS")
		)
		(fp_line
			(start -0.67945 0.3048)
			(end -0.67945 -0.305054)
			(stroke
				(width 0.1)
				(type default)
			)
			(layer "F.Fab")
		)
		(fp_line
			(start -0.12065 0.3048)
			(end -0.67945 0.3048)
			(stroke
				(width 0.1)
				(type default)
			)
			(layer "F.Fab")
		)
		(fp_line
			(start 0.120396 0.3048)
			(end 0.120396 0.2794)
			(stroke
				(width 0.1)
				(type default)
			)
			(layer "F.Fab")
		)
		(fp_line
			(start 0.67945 0.3048)
			(end 0.120396 0.3048)
			(stroke
				(width 0.1)
				(type default)
			)
			(layer "F.Fab")
		)
		(fp_line
			(start -0.12065 0.2794)
			(end -0.12065 0.3048)
			(stroke
				(width 0.1)
				(type default)
			)
			(layer "F.Fab")
		)
		(fp_line
			(start 0.120396 0.2794)
			(end -0.12065 0.2794)
			(stroke
				(width 0.1)
				(type default)
			)
			(layer "F.Fab")
		)
		(fp_line
			(start -0.12065 -0.2794)
			(end 0.12065 -0.2794)
			(stroke
				(width 0.1)
				(type default)
			)
			(layer "F.Fab")
		)
		(fp_line
			(start 0.12065 -0.2794)
			(end 0.12065 -0.3048)
			(stroke
				(width 0.1)
				(type default)
			)
			(layer "F.Fab")
		)
		(fp_line
			(start 0.12065 -0.3048)
			(end 0.67945 -0.3048)
			(stroke
				(width 0.1)
				(type default)
			)
			(layer "F.Fab")
		)
		(fp_line
			(start 0.67945 -0.3048)
			(end 0.67945 0.3048)
			(stroke
				(width 0.1)
				(type default)
			)
			(layer "F.Fab")
		)
		(fp_line
			(start -0.67945 -0.305054)
			(end -0.12065 -0.305054)
			(stroke
				(width 0.1)
				(type default)
			)
			(layer "F.Fab")
		)
		(fp_line
			(start -0.12065 -0.305054)
			(end -0.12065 -0.2794)
			(stroke
				(width 0.1)
				(type default)
			)
			(layer "F.Fab")
		)
		(pad "1" smd circle
			(at -0.40005 0 270)
			(size 0 0)
			(layers "F.Cu" "F.Mask" "F.Paste")
			(net "ESPI_LAD0_DATA_IO2")
		)
		(pad "2" smd circle
			(at 0.40005 0 270)
			(size 0 0)
			(layers "F.Cu" "F.Mask" "F.Paste")
			(net "ESPI_LPC_LAD0_IO2")
		)
	)
	(footprint ""
		(layer "F.Cu")
		(at 92.98305 -354.314252 -90)
		(property "Reference" "PL32"
			(at -7.407148 1.378712 0)
			(unlocked yes)
			(layer "F.SilkS")
			(effects
				(font
					(size 0.7874 0.5842)
					(thickness 0.1524)
				)
				(justify left)
			)
		)
		(property "Value" ""
			(at 0 0 270)
			(layer "F.Fab")
			(effects
				(font
					(size 1.27 1.27)
				)
			)
		)
		(duplicate_pad_numbers_are_jumpers no)
		(fp_line
			(start -4.99999 4.150106)
			(end 4.99999 4.150106)
			(stroke
				(width 0.1524)
				(type default)
			)
			(layer "F.SilkS")
		)
		(fp_line
			(start 4.99999 4.150106)
			(end 4.99999 2.4892)
			(stroke
				(width 0.1524)
				(type default)
			)
			(layer "F.SilkS")
		)
		(fp_line
			(start -4.99999 2.4892)
			(end -4.99999 4.150106)
			(stroke
				(width 0.1524)
				(type default)
			)
			(layer "F.SilkS")
		)
		(fp_line
			(start 4.99999 -2.4892)
			(end 4.99999 -4.150106)
			(stroke
				(width 0.1524)
				(type default)
			)
			(layer "F.SilkS")
		)
		(fp_line
			(start -4.99999 -4.150106)
			(end -4.99999 -2.4892)
			(stroke
				(width 0.1524)
				(type default)
			)
			(layer "F.SilkS")
		)
		(fp_line
			(start 4.99999 -4.150106)
			(end -4.99999 -4.150106)
			(stroke
				(width 0.1524)
				(type default)
			)
			(layer "F.SilkS")
		)
		(fp_line
			(start -4.99999 4.150106)
			(end 4.99999 4.150106)
			(stroke
				(width 0.1)
				(type default)
			)
			(layer "F.Fab")
		)
		(fp_line
			(start 4.99999 4.150106)
			(end 4.99999 -4.150106)
			(stroke
				(width 0.1)
				(type default)
			)
			(layer "F.Fab")
		)
		(fp_line
			(start -4.99999 -4.150106)
			(end -4.99999 4.150106)
			(stroke
				(width 0.1)
				(type default)
			)
			(layer "F.Fab")
		)
		(fp_line
			(start 4.99999 -4.150106)
			(end -4.99999 -4.150106)
			(stroke
				(width 0.1)
				(type default)
			)
			(layer "F.Fab")
		)
		(pad "1" smd rect
			(at -4.174998 0 270)
			(size 2.159 4.699)
			(layers "F.Cu" "F.Mask" "F.Paste")
			(net "P12V_AUX")
		)
		(pad "2" smd rect
			(at 4.174998 0 270)
			(size 2.159 4.699)
			(layers "F.Cu" "F.Mask" "F.Paste")
			(net "SW_P12V_PVCCIN_CPU1_FLT")
		)
	)
	(footprint ""
		(layer "F.Cu")
		(at 448.61988 -95.872808 180)
		(property "Reference" "R3587"
			(at 0 0 180)
			(layer "F.SilkS")
			(hide yes)
			(effects
				(font
					(size 1.27 1.27)
				)
			)
		)
		(property "Value" ""
			(at 0 0 180)
			(layer "F.Fab")
			(effects
				(font
					(size 1.27 1.27)
				)
			)
		)
		(duplicate_pad_numbers_are_jumpers no)
		(fp_line
			(start 0.7874 0.4064)
			(end -0.7874 0.4064)
			(stroke
				(width 0.1524)
				(type default)
			)
			(layer "F.SilkS")
		)
		(fp_line
			(start 0.7874 -0.4064)
			(end 0.7874 0.4064)
			(stroke
				(width 0.1524)
				(type default)
			)
			(layer "F.SilkS")
		)
		(fp_line
			(start -0.7874 0.4064)
			(end -0.7874 -0.4064)
			(stroke
				(width 0.1524)
				(type default)
			)
			(layer "F.SilkS")
		)
		(fp_line
			(start -0.7874 -0.4064)
			(end 0.7874 -0.4064)
			(stroke
				(width 0.1524)
				(type default)
			)
			(layer "F.SilkS")
		)
		(fp_line
			(start 0.67945 0.3048)
			(end 0.120396 0.3048)
			(stroke
				(width 0.1)
				(type default)
			)
			(layer "F.Fab")
		)
		(fp_line
			(start 0.67945 -0.3048)
			(end 0.67945 0.3048)
			(stroke
				(width 0.1)
				(type default)
			)
			(layer "F.Fab")
		)
		(fp_line
			(start 0.12065 -0.2794)
			(end 0.12065 -0.3048)
			(stroke
				(width 0.1)
				(type default)
			)
			(layer "F.Fab")
		)
		(fp_line
			(start 0.12065 -0.3048)
			(end 0.67945 -0.3048)
			(stroke
				(width 0.1)
				(type default)
			)
			(layer "F.Fab")
		)
		(fp_line
			(start 0.120396 0.3048)
			(end 0.120396 0.2794)
			(stroke
				(width 0.1)
				(type default)
			)
			(layer "F.Fab")
		)
		(fp_line
			(start 0.120396 0.2794)
			(end -0.12065 0.2794)
			(stroke
				(width 0.1)
				(type default)
			)
			(layer "F.Fab")
		)
		(fp_line
			(start -0.12065 0.3048)
			(end -0.67945 0.3048)
			(stroke
				(width 0.1)
				(type default)
			)
			(layer "F.Fab")
		)
		(fp_line
			(start -0.12065 0.2794)
			(end -0.12065 0.3048)
			(stroke
				(width 0.1)
				(type default)
			)
			(layer "F.Fab")
		)
		(fp_line
			(start -0.12065 -0.2794)
			(end 0.12065 -0.2794)
			(stroke
				(width 0.1)
				(type default)
			)
			(layer "F.Fab")
		)
		(fp_line
			(start -0.12065 -0.305054)
			(end -0.12065 -0.2794)
			(stroke
				(width 0.1)
				(type default)
			)
			(layer "F.Fab")
		)
		(fp_line
			(start -0.67945 0.3048)
			(end -0.67945 -0.305054)
			(stroke
				(width 0.1)
				(type default)
			)
			(layer "F.Fab")
		)
		(fp_line
			(start -0.67945 -0.305054)
			(end -0.12065 -0.305054)
			(stroke
				(width 0.1)
				(type default)
			)
			(layer "F.Fab")
		)
		(pad "1" smd circle
			(at -0.40005 0 180)
			(size 0 0)
			(layers "F.Cu" "F.Mask" "F.Paste")
			(net "SMB_INA230_3V3AUX_SDA")
		)
		(pad "2" smd circle
			(at 0.40005 0 180)
			(size 0 0)
			(layers "F.Cu" "F.Mask" "F.Paste")
			(net "SMB_INA230_1_3V3AUX_SDA_R")
		)
	)
)
